(kicad_pcb
	(version 20260206)
	(generator "pcbnew")
	(generator_version "10.0")
	(general
		(thickness 1.6)
		(legacy_teardrops no)
	)
	(paper "A4")
	(title_block
		(title "peb — Lightning_PEB_BRD.brd")
		(comment 1 "Lightning (Wiwynn / Facebook NVMe JBOF) / footprints 285-292 of 2563")
	)
	(layers
		(0 "F.Cu" signal "TOP")
		(4 "In1.Cu" signal "L2GND")
		(6 "In2.Cu" signal "L3")
		(8 "In3.Cu" signal "L4VCC")
		(10 "In4.Cu" signal "L5VCC")
		(12 "In5.Cu" signal "L6")
		(14 "In6.Cu" signal "L7GND")
		(2 "B.Cu" signal "BOTTOM")
		(9 "F.Adhes" user "F.Adhesive")
		(11 "B.Adhes" user "B.Adhesive")
		(13 "F.Paste" user "Package Geometry/Pastemask Top")
		(15 "B.Paste" user "Package Geometry/Pastemask Bottom")
		(5 "F.SilkS" user "Ref Des/Silkscreen Top")
		(7 "B.SilkS" user "Ref Des/Silkscreen Bottom")
		(1 "F.Mask" user "Board Geometry/Soldermask Top")
		(3 "B.Mask" user "Board Geometry/Soldermask Bottom")
		(17 "Dwgs.User" user "User.Drawings")
		(19 "Cmts.User" user "User.Comments")
		(21 "Eco1.User" user "User.Eco1")
		(23 "Eco2.User" user "User.Eco2")
		(25 "Edge.Cuts" user "Board Geometry/Outline")
		(27 "Margin" user)
		(31 "F.CrtYd" user "Package Geometry/Place Bound Top")
		(29 "B.CrtYd" user "Package Geometry/Place Bound Bottom")
		(35 "F.Fab" user "Ref Des/Assembly Top")
		(33 "B.Fab" user "Ref Des/Assembly Bottom")
	)
	(footprint ""
		(layer "F.Cu")
		(at 52.197 -199.39 -90)
		(property "Reference" "R888"
			(at 0 0 270)
			(layer "F.SilkS")
			(hide yes)
			(effects
				(font
					(size 1.27 1.27)
				)
			)
		)
		(property "Value" "4K7R2J-2-GP"
			(at 0.064008 -3.993896 270)
			(unlocked yes)
			(layer "F.Fab")
			(hide yes)
			(effects
				(font
					(size 1.016 1.016)
					(thickness 0.1524)
				)
			)
		)
		(property "Device Type" "R402H16"
			(at 0.064008 -5.517896 270)
			(unlocked yes)
			(layer "F.Fab")
			(hide yes)
			(effects
				(font
					(size 1.016 1.016)
					(thickness 0.1524)
				)
			)
		)
		(duplicate_pad_numbers_are_jumpers no)
		(fp_line
			(start -0.508 -0.9398)
			(end -0.508 0.9398)
			(stroke
				(width 0.1524)
				(type default)
			)
			(layer "F.SilkS")
		)
		(fp_line
			(start 0.508 -0.9398)
			(end -0.508 -0.9398)
			(stroke
				(width 0.1524)
				(type default)
			)
			(layer "F.SilkS")
		)
		(fp_rect
			(start -0.508 0.9398)
			(end 0.508 -0.9398)
			(stroke
				(width 0)
				(type default)
			)
			(fill no)
			(layer "F.CrtYd")
		)
		(fp_rect
			(start -0.508 0.9398)
			(end 0.508 -0.9398)
			(stroke
				(width 0)
				(type default)
			)
			(fill no)
			(layer "F.Fab")
		)
		(pad "1" smd custom
			(at 0 -0.4445 270)
			(size 0.1397 0.1397)
			(layers "F.Cu" "F.Mask" "F.Paste")
			(net "P3V3_STBY")
			(options
				(clearance outline)
				(anchor circle)
			)
			(primitives
				(gr_poly
					(pts
						(arc
							(start -0.1778 -0.2794)
							(mid -0.249642 -0.249642)
							(end -0.2794 -0.1778)
						)
						(arc
							(start -0.2794 0.1778)
							(mid -0.249642 0.249642)
							(end -0.1778 0.2794)
						)
						(arc
							(start 0.1778 0.2794)
							(mid 0.249642 0.249642)
							(end 0.2794 0.1778)
						)
						(arc
							(start 0.2794 -0.1778)
							(mid 0.249642 -0.249642)
							(end 0.1778 -0.2794)
						)
					)
					(width 0)
					(fill yes)
				)
			)
		)
		(pad "2" smd custom
			(at 0 0.4445 270)
			(size 0.1397 0.1397)
			(layers "F.Cu" "F.Mask" "F.Paste")
			(net "BUF_I2C7_B_DBP_SCL_R")
			(options
				(clearance outline)
				(anchor circle)
			)
			(primitives
				(gr_poly
					(pts
						(arc
							(start -0.1778 -0.2794)
							(mid -0.249642 -0.249642)
							(end -0.2794 -0.1778)
						)
						(arc
							(start -0.2794 0.1778)
							(mid -0.249642 0.249642)
							(end -0.1778 0.2794)
						)
						(arc
							(start 0.1778 0.2794)
							(mid 0.249642 0.249642)
							(end 0.2794 0.1778)
						)
						(arc
							(start 0.2794 -0.1778)
							(mid 0.249642 -0.249642)
							(end 0.1778 -0.2794)
						)
					)
					(width 0)
					(fill yes)
				)
			)
		)
	)
	(footprint ""
		(layer "F.Cu")
		(at 126.5936 -50.8508 180)
		(property "Reference" "R931"
			(at 0 0 180)
			(layer "F.SilkS")
			(hide yes)
			(effects
				(font
					(size 1.27 1.27)
				)
			)
		)
		(property "Value" "4K7R2F-GP"
			(at 0.064008 -3.993896 180)
			(unlocked yes)
			(layer "F.Fab")
			(hide yes)
			(effects
				(font
					(size 1.016 1.016)
					(thickness 0.1524)
				)
			)
		)
		(property "Device Type" "R402H16"
			(at 0.064008 -5.517896 180)
			(unlocked yes)
			(layer "F.Fab")
			(hide yes)
			(effects
				(font
					(size 1.016 1.016)
					(thickness 0.1524)
				)
			)
		)
		(duplicate_pad_numbers_are_jumpers no)
		(fp_line
			(start 0.508 -0.9398)
			(end -0.508 -0.9398)
			(stroke
				(width 0.1524)
				(type default)
			)
			(layer "F.SilkS")
		)
		(fp_line
			(start -0.508 -0.9398)
			(end -0.508 0.9398)
			(stroke
				(width 0.1524)
				(type default)
			)
			(layer "F.SilkS")
		)
		(fp_rect
			(start -0.508 0.9398)
			(end 0.508 -0.9398)
			(stroke
				(width 0)
				(type default)
			)
			(fill no)
			(layer "F.CrtYd")
		)
		(fp_rect
			(start -0.508 0.9398)
			(end 0.508 -0.9398)
			(stroke
				(width 0)
				(type default)
			)
			(fill no)
			(layer "F.Fab")
		)
		(pad "1" smd custom
			(at 0 -0.4445 180)
			(size 0.1397 0.1397)
			(layers "F.Cu" "F.Mask" "F.Paste")
			(net "P3V3_STBY")
			(options
				(clearance outline)
				(anchor circle)
			)
			(primitives
				(gr_poly
					(pts
						(arc
							(start -0.1778 -0.2794)
							(mid -0.249642 -0.249642)
							(end -0.2794 -0.1778)
						)
						(arc
							(start -0.2794 0.1778)
							(mid -0.249642 0.249642)
							(end -0.1778 0.2794)
						)
						(arc
							(start 0.1778 0.2794)
							(mid 0.249642 0.249642)
							(end 0.2794 0.1778)
						)
						(arc
							(start 0.2794 -0.1778)
							(mid 0.249642 -0.249642)
							(end 0.1778 -0.2794)
						)
					)
					(width 0)
					(fill yes)
				)
			)
		)
		(pad "2" smd custom
			(at 0 0.4445 180)
			(size 0.1397 0.1397)
			(layers "F.Cu" "F.Mask" "F.Paste")
			(net "BMC_ADD1_PWR")
			(options
				(clearance outline)
				(anchor circle)
			)
			(primitives
				(gr_poly
					(pts
						(arc
							(start -0.1778 -0.2794)
							(mid -0.249642 -0.249642)
							(end -0.2794 -0.1778)
						)
						(arc
							(start -0.2794 0.1778)
							(mid -0.249642 0.249642)
							(end -0.1778 0.2794)
						)
						(arc
							(start 0.1778 0.2794)
							(mid 0.249642 0.249642)
							(end 0.2794 0.1778)
						)
						(arc
							(start 0.2794 -0.1778)
							(mid 0.249642 -0.249642)
							(end 0.1778 -0.2794)
						)
					)
					(width 0)
					(fill yes)
				)
			)
		)
	)
	(footprint ""
		(layer "F.Cu")
		(at 26.289 -116.713 180)
		(property "Reference" "R235"
			(at 0 0 180)
			(layer "F.SilkS")
			(hide yes)
			(effects
				(font
					(size 1.27 1.27)
				)
			)
		)
		(property "Value" "100KR2F-L1-GP"
			(at 0.064008 -3.993896 180)
			(unlocked yes)
			(layer "F.Fab")
			(hide yes)
			(effects
				(font
					(size 1.016 1.016)
					(thickness 0.1524)
				)
			)
		)
		(property "Device Type" "R402H16"
			(at 0.064008 -5.517896 180)
			(unlocked yes)
			(layer "F.Fab")
			(hide yes)
			(effects
				(font
					(size 1.016 1.016)
					(thickness 0.1524)
				)
			)
		)
		(duplicate_pad_numbers_are_jumpers no)
		(fp_line
			(start 0.508 -0.9398)
			(end -0.508 -0.9398)
			(stroke
				(width 0.1524)
				(type default)
			)
			(layer "F.SilkS")
		)
		(fp_line
			(start -0.508 -0.9398)
			(end -0.508 0.9398)
			(stroke
				(width 0.1524)
				(type default)
			)
			(layer "F.SilkS")
		)
		(fp_rect
			(start -0.508 0.9398)
			(end 0.508 -0.9398)
			(stroke
				(width 0)
				(type default)
			)
			(fill no)
			(layer "F.CrtYd")
		)
		(fp_rect
			(start -0.508 0.9398)
			(end 0.508 -0.9398)
			(stroke
				(width 0)
				(type default)
			)
			(fill no)
			(layer "F.Fab")
		)
		(pad "1" smd custom
			(at 0 -0.4445 180)
			(size 0.1397 0.1397)
			(layers "F.Cu" "F.Mask" "F.Paste")
			(net "GND")
			(options
				(clearance outline)
				(anchor circle)
			)
			(primitives
				(gr_poly
					(pts
						(arc
							(start -0.1778 -0.2794)
							(mid -0.249642 -0.249642)
							(end -0.2794 -0.1778)
						)
						(arc
							(start -0.2794 0.1778)
							(mid -0.249642 0.249642)
							(end -0.1778 0.2794)
						)
						(arc
							(start 0.1778 0.2794)
							(mid 0.249642 0.249642)
							(end 0.2794 0.1778)
						)
						(arc
							(start 0.2794 -0.1778)
							(mid 0.249642 -0.249642)
							(end 0.1778 -0.2794)
						)
					)
					(width 0)
					(fill yes)
				)
			)
		)
		(pad "2" smd custom
			(at 0 0.4445 180)
			(size 0.1397 0.1397)
			(layers "F.Cu" "F.Mask" "F.Paste")
			(net "TP_BMC0_LPC_LAD1")
			(options
				(clearance outline)
				(anchor circle)
			)
			(primitives
				(gr_poly
					(pts
						(arc
							(start -0.1778 -0.2794)
							(mid -0.249642 -0.249642)
							(end -0.2794 -0.1778)
						)
						(arc
							(start -0.2794 0.1778)
							(mid -0.249642 0.249642)
							(end -0.1778 0.2794)
						)
						(arc
							(start 0.1778 0.2794)
							(mid 0.249642 0.249642)
							(end 0.2794 0.1778)
						)
						(arc
							(start 0.2794 -0.1778)
							(mid 0.249642 -0.249642)
							(end 0.1778 -0.2794)
						)
					)
					(width 0)
					(fill yes)
				)
			)
		)
	)
	(footprint ""
		(layer "F.Cu")
		(at 200.4314 -0.2794 -90)
		(property "Reference" "R543"
			(at 0 0 270)
			(layer "F.SilkS")
			(hide yes)
			(effects
				(font
					(size 1.27 1.27)
				)
			)
		)
		(property "Value" "330R1210J-GP"
			(at 0.0889 -6.9977 270)
			(unlocked yes)
			(layer "F.Fab")
			(hide yes)
			(effects
				(font
					(size 1.016 1.016)
					(thickness 0.1524)
				)
			)
		)
		(property "Device Type" "R1210H24"
			(at 0.0635 -8.636 270)
			(unlocked yes)
			(layer "F.Fab")
			(hide yes)
			(effects
				(font
					(size 1.016 1.016)
					(thickness 0.1524)
				)
			)
		)
		(duplicate_pad_numbers_are_jumpers no)
		(fp_line
			(start -1.651 2.413)
			(end -1.651 -2.413)
			(stroke
				(width 0.1524)
				(type default)
			)
			(layer "F.SilkS")
		)
		(fp_line
			(start 1.651 2.413)
			(end -1.651 2.413)
			(stroke
				(width 0.1524)
				(type default)
			)
			(layer "F.SilkS")
		)
		(fp_line
			(start -1.651 -2.413)
			(end 1.651 -2.413)
			(stroke
				(width 0.1524)
				(type default)
			)
			(layer "F.SilkS")
		)
		(fp_line
			(start 1.651 -2.413)
			(end 1.651 2.413)
			(stroke
				(width 0.1524)
				(type default)
			)
			(layer "F.SilkS")
		)
		(fp_poly
			(pts
				(xy -1.651 -2.413) (xy 1.651 -2.413) (xy 1.651 2.413) (xy -1.651 2.413)
			)
			(stroke
				(width 0)
				(type default)
			)
			(fill no)
			(layer "F.CrtYd")
		)
		(fp_poly
			(pts
				(xy -1.651 -2.413) (xy 1.651 -2.413) (xy 1.651 2.413) (xy -1.651 2.413)
			)
			(stroke
				(width 0)
				(type default)
			)
			(fill no)
			(layer "F.Fab")
		)
		(pad "1" smd rect
			(at 0 -1.4732 270)
			(size 2.794 1.397)
			(layers "F.Cu" "F.Mask" "F.Paste")
			(net "P5V_STBY")
		)
		(pad "2" smd rect
			(at 0 1.4732 270)
			(size 2.794 1.397)
			(layers "F.Cu" "F.Mask" "F.Paste")
			(net "ENCLO_LED_RED_R")
		)
	)
	(footprint ""
		(layer "F.Cu")
		(at 335.8896 -170.5102)
		(property "Reference" "R9033"
			(at 0 0 0)
			(layer "F.SilkS")
			(hide yes)
			(effects
				(font
					(size 1.27 1.27)
				)
			)
		)
		(property "Value" "4K7R2F-GP"
			(at 0.064008 -3.993896 0)
			(unlocked yes)
			(layer "F.Fab")
			(hide yes)
			(effects
				(font
					(size 1.016 1.016)
					(thickness 0.1524)
				)
			)
		)
		(property "Device Type" "R402H16"
			(at 0.064008 -5.517896 0)
			(unlocked yes)
			(layer "F.Fab")
			(hide yes)
			(effects
				(font
					(size 1.016 1.016)
					(thickness 0.1524)
				)
			)
		)
		(duplicate_pad_numbers_are_jumpers no)
		(fp_line
			(start -0.508 -0.9398)
			(end -0.508 0.9398)
			(stroke
				(width 0.1524)
				(type default)
			)
			(layer "F.SilkS")
		)
		(fp_line
			(start 0.508 -0.9398)
			(end -0.508 -0.9398)
			(stroke
				(width 0.1524)
				(type default)
			)
			(layer "F.SilkS")
		)
		(fp_rect
			(start -0.508 0.9398)
			(end 0.508 -0.9398)
			(stroke
				(width 0)
				(type default)
			)
			(fill no)
			(layer "F.CrtYd")
		)
		(fp_rect
			(start -0.508 0.9398)
			(end 0.508 -0.9398)
			(stroke
				(width 0)
				(type default)
			)
			(fill no)
			(layer "F.Fab")
		)
		(pad "1" smd custom
			(at 0 -0.4445)
			(size 0.1397 0.1397)
			(layers "F.Cu" "F.Mask" "F.Paste")
			(net "SSD_PERST#4")
			(options
				(clearance outline)
				(anchor circle)
			)
			(primitives
				(gr_poly
					(pts
						(arc
							(start -0.1778 -0.2794)
							(mid -0.249642 -0.249642)
							(end -0.2794 -0.1778)
						)
						(arc
							(start -0.2794 0.1778)
							(mid -0.249642 0.249642)
							(end -0.1778 0.2794)
						)
						(arc
							(start 0.1778 0.2794)
							(mid 0.249642 0.249642)
							(end 0.2794 0.1778)
						)
						(arc
							(start 0.2794 -0.1778)
							(mid 0.249642 -0.249642)
							(end 0.1778 -0.2794)
						)
					)
					(width 0)
					(fill yes)
				)
			)
		)
		(pad "2" smd custom
			(at 0 0.4445)
			(size 0.1397 0.1397)
			(layers "F.Cu" "F.Mask" "F.Paste")
			(net "GND")
			(options
				(clearance outline)
				(anchor circle)
			)
			(primitives
				(gr_poly
					(pts
						(arc
							(start -0.1778 -0.2794)
							(mid -0.249642 -0.249642)
							(end -0.2794 -0.1778)
						)
						(arc
							(start -0.2794 0.1778)
							(mid -0.249642 0.249642)
							(end -0.1778 0.2794)
						)
						(arc
							(start 0.1778 0.2794)
							(mid 0.249642 0.249642)
							(end 0.2794 0.1778)
						)
						(arc
							(start 0.2794 -0.1778)
							(mid 0.249642 -0.249642)
							(end 0.1778 -0.2794)
						)
					)
					(width 0)
					(fill yes)
				)
			)
		)
	)
	(footprint ""
		(layer "F.Cu")
		(at 42.75328 -115.640612)
		(property "Reference" "TP302"
			(at 0 0 0)
			(layer "F.SilkS")
			(hide yes)
			(effects
				(font
					(size 1.27 1.27)
				)
			)
		)
		(property "Value" "TPAD28-2-GP"
			(at -0.0127 -1.6637 0)
			(unlocked yes)
			(layer "F.Fab")
			(hide yes)
			(effects
				(font
					(size 1.016 1.016)
					(thickness 0.1524)
				)
			)
		)
		(property "Device Type" "TPAD28"
			(at -0.0127 -3.1877 0)
			(unlocked yes)
			(layer "F.Fab")
			(hide yes)
			(effects
				(font
					(size 1.016 1.016)
					(thickness 0.1524)
				)
			)
		)
		(duplicate_pad_numbers_are_jumpers no)
		(fp_poly
			(pts
				(arc
					(start 0.3556 0)
					(mid -0.3556 0)
					(end 0.3556 0)
				)
			)
			(stroke
				(width 0)
				(type default)
			)
			(fill no)
			(layer "F.CrtYd")
		)
		(fp_poly
			(pts
				(arc
					(start 0.6096 0)
					(mid -0.6096 0)
					(end 0.6096 0)
				)
			)
			(stroke
				(width 0)
				(type default)
			)
			(fill no)
			(layer "F.Fab")
		)
		(pad "1" smd circle
			(at 0 0)
			(size 0.7112 0.7112)
			(layers "F.Cu" "F.Mask" "F.Paste")
			(net "TP_RGMIICK")
		)
	)
	(footprint ""
		(layer "F.Cu")
		(at 242.824 -23.241)
		(property "Reference" "R793"
			(at 0 0 0)
			(layer "F.SilkS")
			(hide yes)
			(effects
				(font
					(size 1.27 1.27)
				)
			)
		)
		(property "Value" "4K7R2F-GP"
			(at 0.064008 -3.993896 0)
			(unlocked yes)
			(layer "F.Fab")
			(hide yes)
			(effects
				(font
					(size 1.016 1.016)
					(thickness 0.1524)
				)
			)
		)
		(property "Device Type" "R402H16"
			(at 0.064008 -5.517896 0)
			(unlocked yes)
			(layer "F.Fab")
			(hide yes)
			(effects
				(font
					(size 1.016 1.016)
					(thickness 0.1524)
				)
			)
		)
		(duplicate_pad_numbers_are_jumpers no)
		(fp_line
			(start -0.508 -0.9398)
			(end -0.508 0.9398)
			(stroke
				(width 0.1524)
				(type default)
			)
			(layer "F.SilkS")
		)
		(fp_line
			(start 0.508 -0.9398)
			(end -0.508 -0.9398)
			(stroke
				(width 0.1524)
				(type default)
			)
			(layer "F.SilkS")
		)
		(fp_rect
			(start -0.508 0.9398)
			(end 0.508 -0.9398)
			(stroke
				(width 0)
				(type default)
			)
			(fill no)
			(layer "F.CrtYd")
		)
		(fp_rect
			(start -0.508 0.9398)
			(end 0.508 -0.9398)
			(stroke
				(width 0)
				(type default)
			)
			(fill no)
			(layer "F.Fab")
		)
		(pad "1" smd custom
			(at 0 -0.4445)
			(size 0.1397 0.1397)
			(layers "F.Cu" "F.Mask" "F.Paste")
			(net "GND")
			(options
				(clearance outline)
				(anchor circle)
			)
			(primitives
				(gr_poly
					(pts
						(arc
							(start -0.1778 -0.2794)
							(mid -0.249642 -0.249642)
							(end -0.2794 -0.1778)
						)
						(arc
							(start -0.2794 0.1778)
							(mid -0.249642 0.249642)
							(end -0.1778 0.2794)
						)
						(arc
							(start 0.1778 0.2794)
							(mid 0.249642 0.249642)
							(end 0.2794 0.1778)
						)
						(arc
							(start 0.2794 -0.1778)
							(mid 0.249642 -0.249642)
							(end 0.1778 -0.2794)
						)
					)
					(width 0)
					(fill yes)
				)
			)
		)
		(pad "2" smd custom
			(at 0 0.4445)
			(size 0.1397 0.1397)
			(layers "F.Cu" "F.Mask" "F.Paste")
			(net "BOOTSTRAP0")
			(options
				(clearance outline)
				(anchor circle)
			)
			(primitives
				(gr_poly
					(pts
						(arc
							(start -0.1778 -0.2794)
							(mid -0.249642 -0.249642)
							(end -0.2794 -0.1778)
						)
						(arc
							(start -0.2794 0.1778)
							(mid -0.249642 0.249642)
							(end -0.1778 0.2794)
						)
						(arc
							(start 0.1778 0.2794)
							(mid 0.249642 0.249642)
							(end 0.2794 0.1778)
						)
						(arc
							(start 0.2794 -0.1778)
							(mid 0.249642 -0.249642)
							(end 0.1778 -0.2794)
						)
					)
					(width 0)
					(fill yes)
				)
			)
		)
	)
	(footprint ""
		(layer "F.Cu")
		(at 14.5034 -181.102 90)
		(property "Reference" "R1226"
			(at 0 0 90)
			(layer "F.SilkS")
			(hide yes)
			(effects
				(font
					(size 1.27 1.27)
				)
			)
		)
		(property "Value" "11KR2F-L-GP"
			(at 0.064008 -3.993896 90)
			(unlocked yes)
			(layer "F.Fab")
			(hide yes)
			(effects
				(font
					(size 1.016 1.016)
					(thickness 0.1524)
				)
			)
		)
		(property "Device Type" "R402H16"
			(at 0.064008 -5.517896 90)
			(unlocked yes)
			(layer "F.Fab")
			(hide yes)
			(effects
				(font
					(size 1.016 1.016)
					(thickness 0.1524)
				)
			)
		)
		(duplicate_pad_numbers_are_jumpers no)
		(fp_line
			(start 0.508 -0.9398)
			(end -0.508 -0.9398)
			(stroke
				(width 0.1524)
				(type default)
			)
			(layer "F.SilkS")
		)
		(fp_line
			(start -0.508 -0.9398)
			(end -0.508 0.9398)
			(stroke
				(width 0.1524)
				(type default)
			)
			(layer "F.SilkS")
		)
		(fp_rect
			(start -0.508 0.9398)
			(end 0.508 -0.9398)
			(stroke
				(width 0)
				(type default)
			)
			(fill no)
			(layer "F.CrtYd")
		)
		(fp_rect
			(start -0.508 0.9398)
			(end 0.508 -0.9398)
			(stroke
				(width 0)
				(type default)
			)
			(fill no)
			(layer "F.Fab")
		)
		(pad "1" smd custom
			(at 0 -0.4445 90)
			(size 0.1397 0.1397)
			(layers "F.Cu" "F.Mask" "F.Paste")
			(net "MB0_P12V_PWGIN_R")
			(options
				(clearance outline)
				(anchor circle)
			)
			(primitives
				(gr_poly
					(pts
						(arc
							(start -0.1778 -0.2794)
							(mid -0.249642 -0.249642)
							(end -0.2794 -0.1778)
						)
						(arc
							(start -0.2794 0.1778)
							(mid -0.249642 0.249642)
							(end -0.1778 0.2794)
						)
						(arc
							(start 0.1778 0.2794)
							(mid 0.249642 0.249642)
							(end 0.2794 0.1778)
						)
						(arc
							(start 0.2794 -0.1778)
							(mid 0.249642 -0.249642)
							(end 0.1778 -0.2794)
						)
					)
					(width 0)
					(fill yes)
				)
			)
		)
		(pad "2" smd custom
			(at 0 0.4445 90)
			(size 0.1397 0.1397)
			(layers "F.Cu" "F.Mask" "F.Paste")
			(net "AGND_CURRENT_MON")
			(options
				(clearance outline)
				(anchor circle)
			)
			(primitives
				(gr_poly
					(pts
						(arc
							(start -0.1778 -0.2794)
							(mid -0.249642 -0.249642)
							(end -0.2794 -0.1778)
						)
						(arc
							(start -0.2794 0.1778)
							(mid -0.249642 0.249642)
							(end -0.1778 0.2794)
						)
						(arc
							(start 0.1778 0.2794)
							(mid 0.249642 0.249642)
							(end 0.2794 0.1778)
						)
						(arc
							(start 0.2794 -0.1778)
							(mid 0.249642 -0.249642)
							(end 0.1778 -0.2794)
						)
					)
					(width 0)
					(fill yes)
				)
			)
		)
	)
)
